# TIMECARD (Time Appliance Project (Time Card)) — schematic netlist excerpt (pin names and nets, part order shuffled) for the footprints in the layout excerpt that follows; sources: Cadence DE-HDL packaged netlist, KiCad conversion of R4006-B0001-02_R01.brd

U14  74HCT2G125DP_TSSOP8  NC7WV125K8X  pkg SOP8_091_P0197_H035  page 23
  \1oe*\  = SMA4_SIG_OUT_BF_EN_N
  \1a\  = UNNAMED_12_74HCT2G125DPTSSOP8_3
  \2y\  = BF_ANT4_IN
  GND  = SG
  \2a\  = BF_SMA4_SIG_IO_CONN
  \1y\  = BF_SMA4_SIG_IO_CONN
  \2oe*\  = SMA4_SIG_IN_BF_EN_N
  VCC  = XP3R3V_FPGA

(kicad_pcb
	(version 20260206)
	(generator "pcbnew")
	(generator_version "10.0")
	(general
		(thickness 1.6)
		(legacy_teardrops no)
	)
	(paper "A4")
	(title_block
		(title "timecard-production-celestica-r4006 — R4006-B0001-02_R01.brd")
		(comment 1 "Time Appliance Project (Time Card) / footprints 150-150 of 1113")
	)
	(layers
		(0 "F.Cu" signal "TOP")
		(4 "In1.Cu" signal "L02_GND1")
		(6 "In2.Cu" signal "L03_SIG1")
		(8 "In3.Cu" signal "L04_GND2")
		(10 "In4.Cu" signal "L05_VCC1")
		(12 "In5.Cu" signal "L06_VCC2")
		(14 "In6.Cu" signal "L07_GND3")
		(16 "In7.Cu" signal "L08_SIG2")
		(18 "In8.Cu" signal "L09_GND4")
		(2 "B.Cu" signal "BOTTOM")
		(9 "F.Adhes" user "F.Adhesive")
		(11 "B.Adhes" user "B.Adhesive")
		(13 "F.Paste" user "Package Geometry/Pastemask Top")
		(15 "B.Paste" user "Package Geometry/Pastemask Bottom")
		(5 "F.SilkS" user "Ref Des/Silkscreen Top")
		(7 "B.SilkS" user "Ref Des/Silkscreen Bottom")
		(1 "F.Mask" user "Board Geometry/Soldermask Top")
		(3 "B.Mask" user "Board Geometry/Soldermask Bottom")
		(17 "Dwgs.User" user "User.Drawings")
		(19 "Cmts.User" user "User.Comments")
		(21 "Eco1.User" user "User.Eco1")
		(23 "Eco2.User" user "User.Eco2")
		(25 "Edge.Cuts" user "Board Geometry/Outline")
		(27 "Margin" user)
		(31 "F.CrtYd" user "Package Geometry/Place Bound Top")
		(29 "B.CrtYd" user "Package Geometry/Place Bound Bottom")
		(35 "F.Fab" user "Ref Des/Assembly Top")
		(33 "B.Fab" user "Ref Des/Assembly Bottom")
	)
	(footprint ""
		(layer "F.Cu")
		(at 13.899896 -18.10004 -90)
		(property "Reference" "U14"
			(at 3.91541 0.945896 0)
			(unlocked yes)
			(layer "F.SilkS")
			(effects
				(font
					(size 0.7874 0.5842)
					(thickness 0.1524)
				)
			)
		)
		(property "Value" ""
			(at 0 0 270)
			(layer "F.Fab")
			(effects
				(font
					(size 1.27 1.27)
				)
			)
		)
		(property "Device Type" "74HCT2G125DP_TSSOP8-G220-00055A"
			(at 0 2.413 270)
			(unlocked yes)
			(layer "F.Fab")
			(hide yes)
			(effects
				(font
					(size 0.7874 0.5842)
					(thickness 0.1524)
				)
			)
		)
		(property "User Part Number" "PARTNUM*"
			(at 0 3.6068 270)
			(unlocked yes)
			(layer "Cmts.User")
			(hide yes)
			(effects
				(font
					(size 0.7874 0.5842)
					(thickness 0.1524)
				)
			)
		)
		(duplicate_pad_numbers_are_jumpers no)
		(fp_line
			(start -2.426716 1.304036)
			(end -2.426716 -1.304036)
			(stroke
				(width 0.1)
				(type default)
			)
			(layer "F.SilkS")
		)
		(fp_line
			(start 2.426716 1.304036)
			(end -2.426716 1.304036)
			(stroke
				(width 0.1)
				(type default)
			)
			(layer "F.SilkS")
		)
		(fp_line
			(start -2.426716 -1.304036)
			(end 2.426716 -1.304036)
			(stroke
				(width 0.1)
				(type default)
			)
			(layer "F.SilkS")
		)
		(fp_line
			(start 2.426716 -1.304036)
			(end 2.426716 1.304036)
			(stroke
				(width 0.1)
				(type default)
			)
			(layer "F.SilkS")
		)
		(fp_poly
			(pts
				(arc
					(start -2.98196 -1.594104)
					(mid -2.98196 -0.832104)
					(end -2.98196 -1.594104)
				)
			)
			(stroke
				(width 0)
				(type default)
			)
			(fill yes)
			(layer "F.SilkS")
		)
		(fp_poly
			(pts
				(xy -2.680716 1.558036) (xy 2.680716 1.558036) (xy 2.680716 -1.558036) (xy -2.680716 -1.558036)
			)
			(stroke
				(width 0)
				(type default)
			)
			(fill no)
			(layer "F.CrtYd")
		)
		(fp_line
			(start -1.199896 1.050036)
			(end 1.199896 1.050036)
			(stroke
				(width 0.1)
				(type default)
			)
			(layer "F.Fab")
		)
		(fp_line
			(start 1.199896 1.050036)
			(end 1.199896 -1.050036)
			(stroke
				(width 0.1)
				(type default)
			)
			(layer "F.Fab")
		)
		(fp_line
			(start -1.199896 -1.050036)
			(end -1.199896 1.050036)
			(stroke
				(width 0.1)
				(type default)
			)
			(layer "F.Fab")
		)
		(fp_line
			(start 1.199896 -1.050036)
			(end -1.199896 -1.050036)
			(stroke
				(width 0.1)
				(type default)
			)
			(layer "F.Fab")
		)
		(fp_poly
			(pts
				(arc
					(start -1.94437 -1.338326)
					(mid -1.94437 -0.576326)
					(end -1.94437 -1.338326)
				)
			)
			(stroke
				(width 0)
				(type default)
			)
			(fill yes)
			(layer "F.Fab")
		)
		(fp_text user "4"
			(at -2.208022 1.834896 0)
			(unlocked yes)
			(layer "F.SilkS")
			(effects
				(font
					(size 0.635 0.4064)
					(thickness 0.1524)
				)
			)
		)
		(fp_text user "5"
			(at 2.71399 1.834896 0)
			(unlocked yes)
			(layer "F.SilkS")
			(effects
				(font
					(size 0.635 0.4064)
					(thickness 0.1524)
				)
			)
		)
		(fp_text user "8"
			(at 3.125978 -1.975104 0)
			(unlocked yes)
			(layer "F.SilkS")
			(effects
				(font
					(size 0.635 0.4064)
					(thickness 0.1524)
				)
			)
		)
		(fp_text user "4"
			(at -1.781302 1.199896 0)
			(unlocked yes)
			(layer "F.Fab")
			(effects
				(font
					(size 0.7874 0.5842)
					(thickness 0.1524)
				)
			)
		)
		(fp_text user "5"
			(at 1.947926 0.710184 0)
			(unlocked yes)
			(layer "F.Fab")
			(effects
				(font
					(size 0.7874 0.5842)
					(thickness 0.1524)
				)
			)
		)
		(fp_text user "8"
			(at 1.96088 -0.910844 0)
			(unlocked yes)
			(layer "F.Fab")
			(effects
				(font
					(size 0.7874 0.5842)
					(thickness 0.1524)
				)
			)
		)
		(pad "1" smd rect
			(at -1.690116 -0.749808 270)
			(size 0.9652 0.3048)
			(layers "F.Cu" "F.Mask" "F.Paste")
			(net "SMA4_SIG_OUT_BF_EN_N")
		)
		(pad "2" smd rect
			(at -1.690116 -0.249936 270)
			(size 0.9652 0.3048)
			(layers "F.Cu" "F.Mask" "F.Paste")
			(net "UNNAMED_12_74HCT2G125DPTSSOP8_3")
		)
		(pad "3" smd rect
			(at -1.690116 0.249936 270)
			(size 0.9652 0.3048)
			(layers "F.Cu" "F.Mask" "F.Paste")
			(net "BF_ANT4_IN")
		)
		(pad "4" smd rect
			(at -1.690116 0.749808 270)
			(size 0.9652 0.3048)
			(layers "F.Cu" "F.Mask" "F.Paste")
			(net "SG")
		)
		(pad "5" smd rect
			(at 1.690116 0.749808 270)
			(size 0.9652 0.3048)
			(layers "F.Cu" "F.Mask" "F.Paste")
			(net "BF_SMA4_SIG_IO_CONN")
		)
		(pad "6" smd rect
			(at 1.690116 0.249936 270)
			(size 0.9652 0.3048)
			(layers "F.Cu" "F.Mask" "F.Paste")
			(net "BF_SMA4_SIG_IO_CONN")
		)
		(pad "7" smd rect
			(at 1.690116 -0.249936 270)
			(size 0.9652 0.3048)
			(layers "F.Cu" "F.Mask" "F.Paste")
			(net "SMA4_SIG_IN_BF_EN_N")
		)
		(pad "8" smd rect
			(at 1.690116 -0.749808 270)
			(size 0.9652 0.3048)
			(layers "F.Cu" "F.Mask" "F.Paste")
			(net "XP3R3V_FPGA")
		)
	)
)
